(kicad_pcb
	(version 20260206)
	(generator "pcbnew")
	(generator_version "10.0")
	(general
		(thickness 1.6)
		(legacy_teardrops no)
	)
	(paper "A4")
	(title_block
		(title "v2-tray-backplane — ms_tbp_v2.brd")
		(comment 1 "Open CloudServer (Microsoft) / footprints 75-80 of 164")
	)
	(layers
		(0 "F.Cu" signal "TOP")
		(4 "In1.Cu" signal "LYR2")
		(6 "In2.Cu" signal "LYR3")
		(8 "In3.Cu" signal "LYR4")
		(10 "In4.Cu" signal "LYR5")
		(12 "In5.Cu" signal "LYR6")
		(14 "In6.Cu" signal "LYR7")
		(2 "B.Cu" signal "BOTTOM")
		(9 "F.Adhes" user "F.Adhesive")
		(11 "B.Adhes" user "B.Adhesive")
		(13 "F.Paste" user "Package Geometry/Pastemask Top")
		(15 "B.Paste" user "Package Geometry/Pastemask Bottom")
		(5 "F.SilkS" user "Ref Des/Silkscreen Top")
		(7 "B.SilkS" user "Ref Des/Silkscreen Bottom")
		(1 "F.Mask" user "Board Geometry/Soldermask Top")
		(3 "B.Mask" user "Board Geometry/Soldermask Bottom")
		(17 "Dwgs.User" user "User.Drawings")
		(19 "Cmts.User" user "User.Comments")
		(21 "Eco1.User" user "User.Eco1")
		(23 "Eco2.User" user "User.Eco2")
		(25 "Edge.Cuts" user "Board Geometry/Outline")
		(27 "Margin" user)
		(31 "F.CrtYd" user "Package Geometry/Place Bound Top")
		(29 "B.CrtYd" user "Package Geometry/Place Bound Bottom")
		(35 "F.Fab" user "Ref Des/Assembly Top")
		(33 "B.Fab" user "Ref Des/Assembly Bottom")
	)
	(footprint ""
		(layer "F.Cu")
		(at -344.649689 36.82998 180)
		(property "Reference" "J3"
			(at 0 11.834899 0)
			(unlocked yes)
			(layer "F.SilkS")
			(effects
				(font
					(size 0.762 0.5334)
					(thickness 0.1016)
				)
			)
		)
		(property "Value" ""
			(at 0 0 180)
			(layer "F.Fab")
			(effects
				(font
					(size 1.27 1.27)
				)
			)
		)
		(duplicate_pad_numbers_are_jumpers no)
		(fp_line
			(start 5.325001 10.870001)
			(end -5.325001 10.870001)
			(stroke
				(width 0.127)
				(type default)
			)
			(layer "F.SilkS")
		)
		(fp_line
			(start 5.325001 -12.76)
			(end 5.325001 10.870001)
			(stroke
				(width 0.127)
				(type default)
			)
			(layer "F.SilkS")
		)
		(fp_line
			(start 2.775001 -12.76)
			(end 5.325001 -12.76)
			(stroke
				(width 0.127)
				(type default)
			)
			(layer "F.SilkS")
		)
		(fp_line
			(start 2.775001 -42.660001)
			(end 2.775001 -12.76)
			(stroke
				(width 0.127)
				(type default)
			)
			(layer "F.SilkS")
		)
		(fp_line
			(start -2.775001 -12.76)
			(end -2.775001 -42.660001)
			(stroke
				(width 0.127)
				(type default)
			)
			(layer "F.SilkS")
		)
		(fp_line
			(start -2.775001 -42.660001)
			(end 2.775001 -42.660001)
			(stroke
				(width 0.127)
				(type default)
			)
			(layer "F.SilkS")
		)
		(fp_line
			(start -5.325001 10.870001)
			(end -5.325001 -12.76)
			(stroke
				(width 0.127)
				(type default)
			)
			(layer "F.SilkS")
		)
		(fp_line
			(start -5.325001 -12.76)
			(end -2.775001 -12.76)
			(stroke
				(width 0.127)
				(type default)
			)
			(layer "F.SilkS")
		)
		(fp_poly
			(pts
				(arc
					(start 7.3152 0)
					(mid -7.3152 0)
					(end 7.3152 0)
				)
			)
			(stroke
				(width 0)
				(type default)
			)
			(fill no)
			(layer "B.CrtYd")
		)
		(fp_poly
			(pts
				(xy 6.324999 11.869999) (xy -6.324999 11.869999) (xy -6.324999 -13.76) (xy -3.774999 -13.76) (xy -3.774999 -43.659999)
				(xy 3.774999 -43.659999) (xy 3.774999 -13.76) (xy 6.324999 -13.76)
			)
			(stroke
				(width 0)
				(type default)
			)
			(fill no)
			(layer "F.CrtYd")
		)
		(fp_line
			(start 5.325001 10.870001)
			(end -5.325001 10.870001)
			(stroke
				(width 0.1)
				(type default)
			)
			(layer "F.Fab")
		)
		(fp_line
			(start 5.325001 -12.76)
			(end 5.325001 10.870001)
			(stroke
				(width 0.1)
				(type default)
			)
			(layer "F.Fab")
		)
		(fp_line
			(start 2.775001 -12.76)
			(end 5.325001 -12.76)
			(stroke
				(width 0.1)
				(type default)
			)
			(layer "F.Fab")
		)
		(fp_line
			(start 2.775001 -42.660001)
			(end 2.775001 -12.76)
			(stroke
				(width 0.1)
				(type default)
			)
			(layer "F.Fab")
		)
		(fp_line
			(start -2.775001 -12.76)
			(end -2.775001 -42.660001)
			(stroke
				(width 0.1)
				(type default)
			)
			(layer "F.Fab")
		)
		(fp_line
			(start -2.775001 -42.660001)
			(end 2.775001 -42.660001)
			(stroke
				(width 0.1)
				(type default)
			)
			(layer "F.Fab")
		)
		(fp_line
			(start -5.325001 10.870001)
			(end -5.325001 -12.76)
			(stroke
				(width 0.1)
				(type default)
			)
			(layer "F.Fab")
		)
		(fp_line
			(start -5.325001 -12.76)
			(end -2.775001 -12.76)
			(stroke
				(width 0.1)
				(type default)
			)
			(layer "F.Fab")
		)
		(pad "" np_thru_hole circle
			(at 0 -5.629999 180)
			(size 1.27 1.27)
			(drill 3.9624)
			(layers "*.Cu" "*.Mask")
		)
		(pad "" np_thru_hole circle
			(at 0 6.619999 180)
			(size 1.27 1.27)
			(drill 3.9624)
			(layers "*.Cu" "*.Mask")
		)
		(pad "1" thru_hole circle
			(at 0 0 180)
			(size 5.588 5.588)
			(drill 3.9624)
			(layers "*.Cu" "*.Mask")
			(remove_unused_layers no)
			(net "GND")
		)
		(zone
			(layers "F.Cu" "B.Cu" "In1.Cu" "In2.Cu" "In3.Cu" "In4.Cu" "In5.Cu" "In6.Cu")
			(hatch none 0.5)
			(connect_pads
				(clearance 0)
			)
			(min_thickness 0.25)
			(keepout
				(tracks not_allowed)
				(vias allowed)
				(pads allowed)
				(copperpour not_allowed)
				(footprints allowed)
			)
			(placement
				(enabled no)
				(sheetname "")
			)
			(fill
				(thermal_gap 0.5)
				(thermal_bridge_width 0.5)
				(island_removal_mode 0)
			)
			(polygon
				(pts
					(arc
						(start -347.011889 30.20998)
						(mid -342.287489 30.20998)
						(end -347.011889 30.20998)
					)
				)
			)
		)
		(zone
			(layers "F.Cu" "B.Cu" "In1.Cu" "In2.Cu" "In3.Cu" "In4.Cu" "In5.Cu" "In6.Cu")
			(hatch none 0.5)
			(connect_pads
				(clearance 0)
			)
			(min_thickness 0.25)
			(keepout
				(tracks not_allowed)
				(vias allowed)
				(pads allowed)
				(copperpour not_allowed)
				(footprints allowed)
			)
			(placement
				(enabled no)
				(sheetname "")
			)
			(fill
				(thermal_gap 0.5)
				(thermal_bridge_width 0.5)
				(island_removal_mode 0)
			)
			(polygon
				(pts
					(arc
						(start -347.011889 42.459979)
						(mid -342.287489 42.459979)
						(end -347.011889 42.459979)
					)
				)
			)
		)
	)
	(footprint ""
		(layer "F.Cu")
		(at -58.610401 43.345202)
		(property "Reference" "C9"
			(at 2.476401 -0.127102 0)
			(unlocked yes)
			(layer "F.SilkS")
			(effects
				(font
					(size 0.762 0.5334)
					(thickness 0.1016)
				)
			)
		)
		(property "Value" ""
			(at 0 0 0)
			(layer "F.Fab")
			(effects
				(font
					(size 1.27 1.27)
				)
			)
		)
		(duplicate_pad_numbers_are_jumpers no)
		(fp_poly
			(pts
				(xy -0.999299 0.503999) (xy -0.999299 -0.504) (xy 0.9993 -0.504) (xy 0.9993 0.503999)
			)
			(stroke
				(width 0)
				(type default)
			)
			(fill no)
			(layer "F.CrtYd")
		)
		(fp_line
			(start -0.499999 -0.25)
			(end 0.499999 -0.25)
			(stroke
				(width 0.1)
				(type default)
			)
			(layer "F.Fab")
		)
		(fp_line
			(start -0.499999 0.249999)
			(end -0.499999 -0.25)
			(stroke
				(width 0.1)
				(type default)
			)
			(layer "F.Fab")
		)
		(fp_line
			(start 0.499999 -0.25)
			(end 0.499999 0.249999)
			(stroke
				(width 0.1)
				(type default)
			)
			(layer "F.Fab")
		)
		(fp_line
			(start 0.499999 0.249999)
			(end -0.499999 0.249999)
			(stroke
				(width 0.1)
				(type default)
			)
			(layer "F.Fab")
		)
		(pad "1" smd rect
			(at -0.4572 0 90)
			(size 0.508 0.5842)
			(layers "F.Cu" "F.Mask" "F.Paste")
			(net "P3V3_10G_B2_VCCT")
		)
		(pad "2" smd rect
			(at 0.4572 0 90)
			(size 0.508 0.5842)
			(layers "F.Cu" "F.Mask" "F.Paste")
			(net "GND")
		)
	)
	(footprint ""
		(layer "F.Cu")
		(at -63.4746 45.72)
		(property "Reference" "FB3"
			(at -0.9144 1.0541 0)
			(unlocked yes)
			(layer "F.SilkS")
			(effects
				(font
					(size 0.762 0.5334)
					(thickness 0.1016)
				)
				(justify left)
			)
		)
		(property "Value" ""
			(at 0 0 0)
			(layer "F.Fab")
			(effects
				(font
					(size 1.27 1.27)
				)
			)
		)
		(duplicate_pad_numbers_are_jumpers no)
		(fp_poly
			(pts
				(xy -1.016 0.508) (xy -1.016 -0.508) (xy 1.016 -0.508) (xy 1.016 0.508)
			)
			(stroke
				(width 0)
				(type default)
			)
			(fill no)
			(layer "F.CrtYd")
		)
		(fp_line
			(start -0.508 -0.254)
			(end 0.508 -0.254)
			(stroke
				(width 0.1)
				(type default)
			)
			(layer "F.Fab")
		)
		(fp_line
			(start -0.508 0.254)
			(end -0.508 -0.254)
			(stroke
				(width 0.1)
				(type default)
			)
			(layer "F.Fab")
		)
		(fp_line
			(start 0.508 -0.254)
			(end 0.508 0.254)
			(stroke
				(width 0.1)
				(type default)
			)
			(layer "F.Fab")
		)
		(fp_line
			(start 0.508 0.254)
			(end -0.508 0.254)
			(stroke
				(width 0.1)
				(type default)
			)
			(layer "F.Fab")
		)
		(pad "1" smd rect
			(at -0.4572 0 90)
			(size 0.508 0.5842)
			(layers "F.Cu" "F.Mask" "F.Paste")
			(net "UNNAMED_6_FERRITE_I24_A")
		)
		(pad "2" smd rect
			(at 0.4572 0 90)
			(size 0.508 0.5842)
			(layers "F.Cu" "F.Mask" "F.Paste")
			(net "P3V3_10G_B2_VCCR")
		)
	)
	(footprint ""
		(layer "F.Cu")
		(at -284.563401 43.345202 180)
		(property "Reference" "C7"
			(at 2.126399 -0.050698 0)
			(unlocked yes)
			(layer "F.SilkS")
			(effects
				(font
					(size 0.762 0.5334)
					(thickness 0.1016)
				)
			)
		)
		(property "Value" ""
			(at 0 0 180)
			(layer "F.Fab")
			(effects
				(font
					(size 1.27 1.27)
				)
			)
		)
		(duplicate_pad_numbers_are_jumpers no)
		(fp_poly
			(pts
				(xy -0.9993 0.504) (xy -0.9993 -0.503999) (xy 0.999299 -0.503999) (xy 0.999299 0.504)
			)
			(stroke
				(width 0)
				(type default)
			)
			(fill no)
			(layer "F.CrtYd")
		)
		(fp_line
			(start 0.499999 0.25)
			(end -0.499999 0.25)
			(stroke
				(width 0.1)
				(type default)
			)
			(layer "F.Fab")
		)
		(fp_line
			(start 0.499999 -0.249999)
			(end 0.499999 0.25)
			(stroke
				(width 0.1)
				(type default)
			)
			(layer "F.Fab")
		)
		(fp_line
			(start -0.499999 0.25)
			(end -0.499999 -0.249999)
			(stroke
				(width 0.1)
				(type default)
			)
			(layer "F.Fab")
		)
		(fp_line
			(start -0.499999 -0.249999)
			(end 0.499999 -0.249999)
			(stroke
				(width 0.1)
				(type default)
			)
			(layer "F.Fab")
		)
		(pad "1" smd rect
			(at -0.4572 0 270)
			(size 0.508 0.5842)
			(layers "F.Cu" "F.Mask" "F.Paste")
			(net "P3V3_10G_B1_VCCR")
		)
		(pad "2" smd rect
			(at 0.4572 0 270)
			(size 0.508 0.5842)
			(layers "F.Cu" "F.Mask" "F.Paste")
			(net "GND")
		)
	)
	(footprint ""
		(layer "F.Cu")
		(at -46.109689 36.82998 180)
		(property "Reference" "J22"
			(at 3.166311 12.40788 0)
			(unlocked yes)
			(layer "F.SilkS")
			(effects
				(font
					(size 0.762 0.5334)
					(thickness 0.1016)
				)
			)
		)
		(property "Value" ""
			(at 0 0 180)
			(layer "F.Fab")
			(effects
				(font
					(size 1.27 1.27)
				)
			)
		)
		(duplicate_pad_numbers_are_jumpers no)
		(fp_line
			(start 5.325001 10.870001)
			(end -5.325 10.870001)
			(stroke
				(width 0.127)
				(type default)
			)
			(layer "F.SilkS")
		)
		(fp_line
			(start 5.325001 9.27098)
			(end 5.325001 10.870001)
			(stroke
				(width 0.127)
				(type default)
			)
			(layer "F.SilkS")
		)
		(fp_line
			(start 5.325001 -1.88216)
			(end 5.325001 7.36598)
			(stroke
				(width 0.127)
				(type default)
			)
			(layer "F.SilkS")
		)
		(fp_line
			(start 5.325001 -12.76)
			(end 5.325001 -3.14708)
			(stroke
				(width 0.127)
				(type default)
			)
			(layer "F.SilkS")
		)
		(fp_line
			(start 2.775001 -12.76)
			(end 5.325001 -12.76)
			(stroke
				(width 0.127)
				(type default)
			)
			(layer "F.SilkS")
		)
		(fp_line
			(start 2.775001 -42.660001)
			(end 2.775001 -12.76)
			(stroke
				(width 0.127)
				(type default)
			)
			(layer "F.SilkS")
		)
		(fp_line
			(start -2.775 -12.76)
			(end -2.775 -42.660001)
			(stroke
				(width 0.127)
				(type default)
			)
			(layer "F.SilkS")
		)
		(fp_line
			(start -2.775 -42.660001)
			(end 2.775001 -42.660001)
			(stroke
				(width 0.127)
				(type default)
			)
			(layer "F.SilkS")
		)
		(fp_line
			(start -5.325 10.870001)
			(end -5.325 -12.76)
			(stroke
				(width 0.127)
				(type default)
			)
			(layer "F.SilkS")
		)
		(fp_line
			(start -5.325 -12.76)
			(end -2.775 -12.76)
			(stroke
				(width 0.127)
				(type default)
			)
			(layer "F.SilkS")
		)
		(fp_poly
			(pts
				(arc
					(start -7.3152 0)
					(mid 7.3152 0)
					(end -7.3152 0)
				)
			)
			(stroke
				(width 0)
				(type default)
			)
			(fill no)
			(layer "B.CrtYd")
		)
		(fp_poly
			(pts
				(xy 6.324999 11.869999) (xy -6.324998 11.869999) (xy -6.324998 -13.76) (xy -3.774998 -13.76) (xy -3.774998 -43.659999)
				(xy 3.774999 -43.659999) (xy 3.774999 -13.76) (xy 6.324999 -13.76)
			)
			(stroke
				(width 0)
				(type default)
			)
			(fill no)
			(layer "F.CrtYd")
		)
		(fp_line
			(start 5.325001 10.870001)
			(end -5.325 10.870001)
			(stroke
				(width 0.1)
				(type default)
			)
			(layer "F.Fab")
		)
		(fp_line
			(start 5.325001 -12.76)
			(end 5.325001 10.870001)
			(stroke
				(width 0.1)
				(type default)
			)
			(layer "F.Fab")
		)
		(fp_line
			(start 2.775001 -12.76)
			(end 5.325001 -12.76)
			(stroke
				(width 0.1)
				(type default)
			)
			(layer "F.Fab")
		)
		(fp_line
			(start 2.775001 -42.660001)
			(end 2.775001 -12.76)
			(stroke
				(width 0.1)
				(type default)
			)
			(layer "F.Fab")
		)
		(fp_line
			(start -2.775 -12.76)
			(end -2.775 -42.660001)
			(stroke
				(width 0.1)
				(type default)
			)
			(layer "F.Fab")
		)
		(fp_line
			(start -2.775 -42.660001)
			(end 2.775001 -42.660001)
			(stroke
				(width 0.1)
				(type default)
			)
			(layer "F.Fab")
		)
		(fp_line
			(start -5.325 10.870001)
			(end -5.325 -12.76)
			(stroke
				(width 0.1)
				(type default)
			)
			(layer "F.Fab")
		)
		(fp_line
			(start -5.325 -12.76)
			(end -2.775 -12.76)
			(stroke
				(width 0.1)
				(type default)
			)
			(layer "F.Fab")
		)
		(pad "" np_thru_hole circle
			(at 0 -5.629999 180)
			(size 1.27 1.27)
			(drill 3.9624)
			(layers "*.Cu" "*.Mask")
		)
		(pad "" np_thru_hole circle
			(at 0 6.619999 180)
			(size 1.27 1.27)
			(drill 3.9624)
			(layers "*.Cu" "*.Mask")
		)
		(pad "1" thru_hole circle
			(at 0 0 180)
			(size 5.588 5.588)
			(drill 3.9624)
			(layers "*.Cu" "*.Mask")
			(remove_unused_layers no)
			(net "GND")
		)
		(zone
			(layers "F.Cu" "B.Cu" "In1.Cu" "In2.Cu" "In3.Cu" "In4.Cu" "In5.Cu" "In6.Cu")
			(hatch none 0.5)
			(connect_pads
				(clearance 0)
			)
			(min_thickness 0.25)
			(keepout
				(tracks not_allowed)
				(vias allowed)
				(pads allowed)
				(copperpour not_allowed)
				(footprints allowed)
			)
			(placement
				(enabled no)
				(sheetname "")
			)
			(fill
				(thermal_gap 0.5)
				(thermal_bridge_width 0.5)
				(island_removal_mode 0)
			)
			(polygon
				(pts
					(arc
						(start -43.747489 30.20998)
						(mid -48.471889 30.20998)
						(end -43.747489 30.20998)
					)
				)
			)
		)
		(zone
			(layers "F.Cu" "B.Cu" "In1.Cu" "In2.Cu" "In3.Cu" "In4.Cu" "In5.Cu" "In6.Cu")
			(hatch none 0.5)
			(connect_pads
				(clearance 0)
			)
			(min_thickness 0.25)
			(keepout
				(tracks not_allowed)
				(vias allowed)
				(pads allowed)
				(copperpour not_allowed)
				(footprints allowed)
			)
			(placement
				(enabled no)
				(sheetname "")
			)
			(fill
				(thermal_gap 0.5)
				(thermal_bridge_width 0.5)
				(island_removal_mode 0)
			)
			(polygon
				(pts
					(arc
						(start -43.747489 42.459979)
						(mid -48.471889 42.459979)
						(end -43.747489 42.459979)
					)
				)
			)
		)
	)
	(footprint ""
		(layer "F.Cu")
		(at -296.145801 4.127602)
		(property "Reference" "R20"
			(at 3.067901 0.528218 0)
			(unlocked yes)
			(layer "F.SilkS")
			(effects
				(font
					(size 0.762 0.5334)
					(thickness 0.1016)
				)
			)
		)
		(property "Value" ""
			(at 0 0 0)
			(layer "F.Fab")
			(effects
				(font
					(size 1.27 1.27)
				)
			)
		)
		(duplicate_pad_numbers_are_jumpers no)
		(fp_line
			(start 0 -0.381)
			(end 0 0.381)
			(stroke
				(width 0.127)
				(type default)
			)
			(layer "F.SilkS")
		)
		(fp_poly
			(pts
				(xy 1.255601 0.656399) (xy -1.255601 0.656399) (xy -1.255601 -0.6564) (xy 1.255601 -0.6564)
			)
			(stroke
				(width 0)
				(type default)
			)
			(fill no)
			(layer "F.CrtYd")
		)
		(fp_line
			(start -0.800001 -0.4)
			(end -0.800001 0.399999)
			(stroke
				(width 0.1)
				(type default)
			)
			(layer "F.Fab")
		)
		(fp_line
			(start -0.800001 0.399999)
			(end 0.800001 0.399999)
			(stroke
				(width 0.1)
				(type default)
			)
			(layer "F.Fab")
		)
		(fp_line
			(start 0.800001 -0.4)
			(end -0.800001 -0.4)
			(stroke
				(width 0.1)
				(type default)
			)
			(layer "F.Fab")
		)
		(fp_line
			(start 0.800001 0.399999)
			(end 0.800001 -0.4)
			(stroke
				(width 0.1)
				(type default)
			)
			(layer "F.Fab")
		)
		(pad "1" smd rect
			(at -0.650001 0)
			(size 0.7112 0.8128)
			(layers "F.Cu" "F.Mask" "F.Paste")
			(net "P3V3_B1_QSFP")
		)
		(pad "2" smd rect
			(at 0.650001 0 180)
			(size 0.7112 0.8128)
			(layers "F.Cu" "F.Mask" "F.Paste")
			(net "ETH10G_B1_TX_DIS")
		)
	)
)
